(kicad_pcb
	(version 20260206)
	(generator "pcbnew")
	(generator_version "10.0")
	(general
		(thickness 1.6)
		(legacy_teardrops no)
	)
	(paper "A4")
	(title_block
		(title "03242023_DA0F0TMBIJ0_F0T_Motherboard_J_brd_V01_OCP.brd")
		(comment 1 "Grand Teton / footprint 1585 of 6105 (U4), pads 450-561 of 749")
	)
	(layers
		(0 "F.Cu" signal "TOP")
		(4 "In1.Cu" signal "GND")
		(6 "In2.Cu" signal "IN1")
		(8 "In3.Cu" signal "GND1")
		(10 "In4.Cu" signal "IN2")
		(12 "In5.Cu" signal "GND2")
		(14 "In6.Cu" signal "IN3")
		(16 "In7.Cu" signal "GND3")
		(18 "In8.Cu" signal "VCC")
		(20 "In9.Cu" signal "VCC1")
		(22 "In10.Cu" signal "GND4")
		(24 "In11.Cu" signal "IN4")
		(26 "In12.Cu" signal "GND5")
		(28 "In13.Cu" signal "IN5")
		(30 "In14.Cu" signal "GND6")
		(32 "In15.Cu" signal "IN6")
		(34 "In16.Cu" signal "GND7")
		(2 "B.Cu" signal "BOTTOM")
		(9 "F.Adhes" user "F.Adhesive")
		(11 "B.Adhes" user "B.Adhesive")
		(13 "F.Paste" user "Package Geometry/Pastemask Top")
		(15 "B.Paste" user "Package Geometry/Pastemask Bottom")
		(5 "F.SilkS" user "Ref Des/Silkscreen Top")
		(7 "B.SilkS" user "Ref Des/Silkscreen Bottom")
		(1 "F.Mask" user "Board Geometry/Soldermask Top")
		(3 "B.Mask" user "Board Geometry/Soldermask Bottom")
		(17 "Dwgs.User" user "User.Drawings")
		(19 "Cmts.User" user "User.Comments")
		(21 "Eco1.User" user "User.Eco1")
		(23 "Eco2.User" user "User.Eco2")
		(25 "Edge.Cuts" user "Board Geometry/Outline")
		(27 "Margin" user)
		(31 "F.CrtYd" user "Package Geometry/Place Bound Top")
		(29 "B.CrtYd" user "Package Geometry/Place Bound Bottom")
		(35 "F.Fab" user "Ref Des/Assembly Top")
		(33 "B.Fab" user "Ref Des/Assembly Bottom")
	)
	(footprint ""
		(layer "F.Cu")
		(at 336.899758 -48.450246)
		(property "Reference" "U4"
			(at -13.479018 -11.486896 0)
			(unlocked yes)
			(layer "F.SilkS")
			(effects
				(font
					(size 0.7874 0.5842)
					(thickness 0.1524)
				)
				(justify left)
			)
		)
		(property "Value" ""
			(at 0 0 0)
			(layer "F.Fab")
			(effects
				(font
					(size 1.27 1.27)
				)
			)
		)
		(duplicate_pad_numbers_are_jumpers no)
		(pad "BG3" smd circle
			(at -9.65962 10.815066 180)
			(size 0.4064 0.4064)
			(layers "F.Cu" "F.Mask" "F.Paste")
			(net "TP_PCH_CGC_DUT_DETECTED")
		)
		(pad "BG4" smd circle
			(at -9.0043 10.815066 180)
			(size 0.4064 0.4064)
			(layers "F.Cu" "F.Mask" "F.Paste")
			(net "GND")
		)
		(pad "BG6" smd circle
			(at -8.003794 10.815066 180)
			(size 0.3048 0.3048)
			(layers "F.Cu" "F.Mask" "F.Paste")
			(net "GND")
		)
		(pad "BG8" smd oval
			(at -7.003288 10.815066 180)
			(size 0.254 0.3302)
			(layers "F.Cu" "F.Mask" "F.Paste")
			(net "FM_INTRUDER_HDR_PCH_N")
		)
		(pad "BG10" smd oval
			(at -6.002782 10.815066 180)
			(size 0.254 0.3302)
			(layers "F.Cu" "F.Mask" "F.Paste")
			(net "GND")
		)
		(pad "BG12" smd oval
			(at -5.002276 10.815066 180)
			(size 0.254 0.3302)
			(layers "F.Cu" "F.Mask" "F.Paste")
			(net "ESPI_LAD0_DATA_IO0")
		)
		(pad "BG14" smd oval
			(at -4.002024 10.815066 180)
			(size 0.254 0.3302)
			(layers "F.Cu" "F.Mask" "F.Paste")
			(net "PD_PCH_GPPC_A_19")
		)
		(pad "BG16" smd oval
			(at -3.001518 10.815066 180)
			(size 0.254 0.3302)
			(layers "F.Cu" "F.Mask" "F.Paste")
			(net "M2_SSD0_CLKREQ_EN_N")
		)
		(pad "BG18" smd oval
			(at -2.001012 10.815066 180)
			(size 0.254 0.3302)
			(layers "F.Cu" "F.Mask" "F.Paste")
			(net "E1S_0_CLKREQ_N")
		)
		(pad "BG20" smd oval
			(at -1.000506 10.815066 180)
			(size 0.254 0.3302)
			(layers "F.Cu" "F.Mask" "F.Paste")
			(net "IRQ_LPC_PIRQA_N_ESPI_ALERT0_N")
		)
		(pad "BG22" smd oval
			(at 0 10.815066 180)
			(size 0.254 0.3302)
			(layers "F.Cu" "F.Mask" "F.Paste")
			(net "PU_OC6_USB_N")
		)
		(pad "BG24" smd oval
			(at 1.000506 10.815066 180)
			(size 0.254 0.3302)
			(layers "F.Cu" "F.Mask" "F.Paste")
			(net "PU_OC5_USB_N")
		)
		(pad "BG26" smd oval
			(at 2.001012 10.815066 180)
			(size 0.254 0.3302)
			(layers "F.Cu" "F.Mask" "F.Paste")
			(net "PU_OC4_USB_N")
		)
		(pad "BG28" smd oval
			(at 3.001518 10.815066 180)
			(size 0.254 0.3302)
			(layers "F.Cu" "F.Mask" "F.Paste")
			(net "PU_OC3_USB_N")
		)
		(pad "BG30" smd oval
			(at 4.002024 10.815066 180)
			(size 0.254 0.3302)
			(layers "F.Cu" "F.Mask" "F.Paste")
			(net "PU_OC2_USB_N")
		)
		(pad "BG32" smd oval
			(at 5.002276 10.815066 180)
			(size 0.254 0.3302)
			(layers "F.Cu" "F.Mask" "F.Paste")
			(net "USB_OC1_REAR_R_N")
		)
		(pad "BG34" smd oval
			(at 6.002782 10.815066 180)
			(size 0.254 0.3302)
			(layers "F.Cu" "F.Mask" "F.Paste")
			(net "GND")
		)
		(pad "BG36" smd oval
			(at 7.003288 10.815066 180)
			(size 0.254 0.3302)
			(layers "F.Cu" "F.Mask" "F.Paste")
			(net "NC_PCH_RSVD<17>")
		)
		(pad "BG38" smd circle
			(at 8.003794 10.815066 180)
			(size 0.4064 0.4064)
			(layers "F.Cu" "F.Mask" "F.Paste")
			(net "GND")
		)
		(pad "BG40" smd circle
			(at 9.0043 10.815066 180)
			(size 0.4064 0.4064)
			(layers "F.Cu" "F.Mask" "F.Paste")
			(net "GND")
		)
		(pad "BG41" smd circle
			(at 9.65962 10.815066 180)
			(size 0.4064 0.4064)
			(layers "F.Cu" "F.Mask" "F.Paste")
			(net "GND")
		)
		(pad "C3" smd circle
			(at -9.65962 -10.159746 180)
			(size 0.4064 0.4064)
			(layers "F.Cu" "F.Mask" "F.Paste")
			(net "GND")
		)
		(pad "C4" smd circle
			(at -9.0043 -9.984994 180)
			(size 0.3048 0.3048)
			(layers "F.Cu" "F.Mask" "F.Paste")
			(net "GND")
		)
		(pad "C6" smd circle
			(at -8.003794 -9.984994 180)
			(size 0.3048 0.3048)
			(layers "F.Cu" "F.Mask" "F.Paste")
			(net "TP_CLK_100M_PCH_15_DP")
		)
		(pad "C8" smd circle
			(at -7.003288 -9.984994 180)
			(size 0.3048 0.3048)
			(layers "F.Cu" "F.Mask" "F.Paste")
			(net "TP_CLK_100M_PCH_13_DP")
		)
		(pad "C10" smd circle
			(at -6.002782 -9.984994 180)
			(size 0.3048 0.3048)
			(layers "F.Cu" "F.Mask" "F.Paste")
			(net "TP_CLK_100M_PCH_12_DP")
		)
		(pad "C12" smd circle
			(at -5.002276 -9.984994 180)
			(size 0.3048 0.3048)
			(layers "F.Cu" "F.Mask" "F.Paste")
			(net "TP_CLK_100M_PCH_5_DP")
		)
		(pad "C14" smd circle
			(at -4.002024 -9.984994 180)
			(size 0.3048 0.3048)
			(layers "F.Cu" "F.Mask" "F.Paste")
			(net "TP_CLK_100M_PCH_7_DP")
		)
		(pad "C16" smd circle
			(at -3.001518 -9.984994 180)
			(size 0.3048 0.3048)
			(layers "F.Cu" "F.Mask" "F.Paste")
			(net "TP_CLK_100M_PCH_0_DP")
		)
		(pad "C18" smd circle
			(at -2.001012 -9.984994 180)
			(size 0.3048 0.3048)
			(layers "F.Cu" "F.Mask" "F.Paste")
			(net "TP_CLK_100M_PCH_16_DP")
		)
		(pad "C20" smd circle
			(at -1.000506 -9.984994 180)
			(size 0.3048 0.3048)
			(layers "F.Cu" "F.Mask" "F.Paste")
			(net "GND")
		)
		(pad "C22" smd circle
			(at 0 -9.984994 180)
			(size 0.3048 0.3048)
			(layers "F.Cu" "F.Mask" "F.Paste")
			(net "GND")
		)
		(pad "C24" smd circle
			(at 1.000506 -9.984994 180)
			(size 0.3048 0.3048)
			(layers "F.Cu" "F.Mask" "F.Paste")
			(net "GND")
		)
		(pad "C26" smd circle
			(at 2.001012 -9.984994 180)
			(size 0.3048 0.3048)
			(layers "F.Cu" "F.Mask" "F.Paste")
			(net "GND")
		)
		(pad "C28" smd circle
			(at 3.001518 -9.984994 180)
			(size 0.3048 0.3048)
			(layers "F.Cu" "F.Mask" "F.Paste")
			(net "CLK_25M_PCH_CPU1_DN")
		)
		(pad "C30" smd circle
			(at 4.002024 -9.984994 180)
			(size 0.3048 0.3048)
			(layers "F.Cu" "F.Mask" "F.Paste")
			(net "DMI_CPU0_PCH_TX_C_DP<0>")
		)
		(pad "C32" smd circle
			(at 5.002276 -9.984994 180)
			(size 0.3048 0.3048)
			(layers "F.Cu" "F.Mask" "F.Paste")
			(net "DMI_CPU0_PCH_TX_C_DP<2>")
		)
		(pad "C34" smd circle
			(at 6.002782 -9.984994 180)
			(size 0.3048 0.3048)
			(layers "F.Cu" "F.Mask" "F.Paste")
			(net "DMI_CPU0_PCH_TX_C_DP<4>")
		)
		(pad "C36" smd circle
			(at 7.003288 -9.984994 180)
			(size 0.3048 0.3048)
			(layers "F.Cu" "F.Mask" "F.Paste")
			(net "DMI_CPU0_PCH_TX_C_DP<6>")
		)
		(pad "C38" smd circle
			(at 8.003794 -9.984994 180)
			(size 0.3048 0.3048)
			(layers "F.Cu" "F.Mask" "F.Paste")
			(net "GND")
		)
		(pad "C40" smd circle
			(at 9.0043 -9.984994 180)
			(size 0.3048 0.3048)
			(layers "F.Cu" "F.Mask" "F.Paste")
			(net "NC_PCH_RSVD<8>")
		)
		(pad "C41" smd circle
			(at 9.65962 -10.159746 180)
			(size 0.3048 0.3048)
			(layers "F.Cu" "F.Mask" "F.Paste")
			(net "GND")
		)
		(pad "C43" smd circle
			(at 10.31494 -10.159746 180)
			(size 0.4064 0.4064)
			(layers "F.Cu" "F.Mask" "F.Paste")
			(net "GND")
		)
		(pad "D1" smd circle
			(at -10.31494 -9.50468 180)
			(size 0.4064 0.4064)
			(layers "F.Cu" "F.Mask" "F.Paste")
			(net "GND")
		)
		(pad "D3" smd circle
			(at -9.484868 -9.50468 180)
			(size 0.3048 0.3048)
			(layers "F.Cu" "F.Mask" "F.Paste")
			(net "GND")
		)
		(pad "D5" smd circle
			(at -8.504174 -9.569958 180)
			(size 0.3048 0.3048)
			(layers "F.Cu" "F.Mask" "F.Paste")
			(net "GND")
		)
		(pad "D7" smd circle
			(at -7.503668 -9.569958 180)
			(size 0.3048 0.3048)
			(layers "F.Cu" "F.Mask" "F.Paste")
			(net "TP_CLK_100M_PCH_14_DP")
		)
		(pad "D9" smd circle
			(at -6.503162 -9.569958 180)
			(size 0.3048 0.3048)
			(layers "F.Cu" "F.Mask" "F.Paste")
			(net "GND")
		)
		(pad "D11" smd circle
			(at -5.502656 -9.569958 180)
			(size 0.3048 0.3048)
			(layers "F.Cu" "F.Mask" "F.Paste")
			(net "CLK_100M_BMC_P3E_DP")
		)
		(pad "D13" smd circle
			(at -4.50215 -9.569958 180)
			(size 0.3048 0.3048)
			(layers "F.Cu" "F.Mask" "F.Paste")
			(net "GND")
		)
		(pad "D15" smd circle
			(at -3.501644 -9.569958 180)
			(size 0.3048 0.3048)
			(layers "F.Cu" "F.Mask" "F.Paste")
			(net "TP_CLK_100M_PCH_9_DP")
		)
		(pad "D17" smd circle
			(at -2.501138 -9.569958 180)
			(size 0.3048 0.3048)
			(layers "F.Cu" "F.Mask" "F.Paste")
			(net "CLK_100M_E1S_0_R_DP")
		)
		(pad "D19" smd circle
			(at -1.500632 -9.569958 180)
			(size 0.3048 0.3048)
			(layers "F.Cu" "F.Mask" "F.Paste")
			(net "TP_CLK_100M_PCH_4_DP")
		)
		(pad "D21" smd circle
			(at -0.500126 -9.569958 180)
			(size 0.3048 0.3048)
			(layers "F.Cu" "F.Mask" "F.Paste")
			(net "CLK_100M_CK440_PCH_EXTCLK_DN")
		)
		(pad "D23" smd circle
			(at 0.500126 -9.569958 180)
			(size 0.3048 0.3048)
			(layers "F.Cu" "F.Mask" "F.Paste")
			(net "XTAL_PCH_25M_OUT")
		)
		(pad "D25" smd circle
			(at 1.500632 -9.569958 180)
			(size 0.3048 0.3048)
			(layers "F.Cu" "F.Mask" "F.Paste")
			(net "CLK_25M_PCH_REF_NS_DN")
		)
		(pad "D27" smd circle
			(at 2.501138 -9.569958 180)
			(size 0.3048 0.3048)
			(layers "F.Cu" "F.Mask" "F.Paste")
			(net "CLK_25M_PCH_CPU0_DN")
		)
		(pad "D29" smd circle
			(at 3.501644 -9.569958 180)
			(size 0.3048 0.3048)
			(layers "F.Cu" "F.Mask" "F.Paste")
			(net "GND")
		)
		(pad "D31" smd circle
			(at 4.50215 -9.569958 180)
			(size 0.3048 0.3048)
			(layers "F.Cu" "F.Mask" "F.Paste")
			(net "DMI_CPU0_PCH_TX_C_DP<1>")
		)
		(pad "D33" smd circle
			(at 5.502656 -9.569958 180)
			(size 0.3048 0.3048)
			(layers "F.Cu" "F.Mask" "F.Paste")
			(net "DMI_CPU0_PCH_TX_C_DP<3>")
		)
		(pad "D35" smd circle
			(at 6.503162 -9.569958 180)
			(size 0.3048 0.3048)
			(layers "F.Cu" "F.Mask" "F.Paste")
			(net "DMI_CPU0_PCH_TX_C_DP<5>")
		)
		(pad "D37" smd circle
			(at 7.503668 -9.569958 180)
			(size 0.3048 0.3048)
			(layers "F.Cu" "F.Mask" "F.Paste")
			(net "DMI_CPU0_PCH_TX_C_DP<7>")
		)
		(pad "D39" smd circle
			(at 8.504174 -9.569958 180)
			(size 0.3048 0.3048)
			(layers "F.Cu" "F.Mask" "F.Paste")
			(net "NC_PCH_RSVD<9>")
		)
		(pad "D41" smd circle
			(at 9.484868 -9.50468 180)
			(size 0.3048 0.3048)
			(layers "F.Cu" "F.Mask" "F.Paste")
			(net "GND")
		)
		(pad "D43" smd circle
			(at 10.31494 -9.50468 180)
			(size 0.4064 0.4064)
			(layers "F.Cu" "F.Mask" "F.Paste")
			(net "GND")
		)
		(pad "E2" smd circle
			(at -9.899904 -9.0043 180)
			(size 0.3048 0.3048)
			(layers "F.Cu" "F.Mask" "F.Paste")
			(net "GND")
		)
		(pad "E4" smd circle
			(at -9.069832 -9.0043 180)
			(size 0.3048 0.3048)
			(layers "F.Cu" "F.Mask" "F.Paste")
			(net "TP_PCH_CPU_MEMTRIP_N")
		)
		(pad "E6" smd circle
			(at -8.003794 -9.154922 180)
			(size 0.3048 0.3048)
			(layers "F.Cu" "F.Mask" "F.Paste")
			(net "GND")
		)
		(pad "E8" smd circle
			(at -7.003288 -9.154922 180)
			(size 0.3048 0.3048)
			(layers "F.Cu" "F.Mask" "F.Paste")
			(net "GND")
		)
		(pad "E10" smd circle
			(at -6.002782 -9.154922 180)
			(size 0.3048 0.3048)
			(layers "F.Cu" "F.Mask" "F.Paste")
			(net "GND")
		)
		(pad "E12" smd circle
			(at -5.002276 -9.154922 180)
			(size 0.3048 0.3048)
			(layers "F.Cu" "F.Mask" "F.Paste")
			(net "GND")
		)
		(pad "E14" smd circle
			(at -4.002024 -9.154922 180)
			(size 0.3048 0.3048)
			(layers "F.Cu" "F.Mask" "F.Paste")
			(net "GND")
		)
		(pad "E16" smd circle
			(at -3.001518 -9.154922 180)
			(size 0.3048 0.3048)
			(layers "F.Cu" "F.Mask" "F.Paste")
			(net "GND")
		)
		(pad "E18" smd circle
			(at -2.001012 -9.154922 180)
			(size 0.3048 0.3048)
			(layers "F.Cu" "F.Mask" "F.Paste")
			(net "GND")
		)
		(pad "E20" smd circle
			(at -1.000506 -9.154922 180)
			(size 0.3048 0.3048)
			(layers "F.Cu" "F.Mask" "F.Paste")
			(net "GND")
		)
		(pad "E22" smd circle
			(at 0 -9.154922 180)
			(size 0.3048 0.3048)
			(layers "F.Cu" "F.Mask" "F.Paste")
			(net "GND")
		)
		(pad "E24" smd circle
			(at 1.000506 -9.154922 180)
			(size 0.3048 0.3048)
			(layers "F.Cu" "F.Mask" "F.Paste")
			(net "GND")
		)
		(pad "E26" smd circle
			(at 2.001012 -9.154922 180)
			(size 0.3048 0.3048)
			(layers "F.Cu" "F.Mask" "F.Paste")
			(net "GND")
		)
		(pad "E28" smd circle
			(at 3.001518 -9.154922 180)
			(size 0.3048 0.3048)
			(layers "F.Cu" "F.Mask" "F.Paste")
			(net "GND")
		)
		(pad "E30" smd circle
			(at 4.002024 -9.154922 180)
			(size 0.3048 0.3048)
			(layers "F.Cu" "F.Mask" "F.Paste")
			(net "GND")
		)
		(pad "E32" smd circle
			(at 5.002276 -9.154922 180)
			(size 0.3048 0.3048)
			(layers "F.Cu" "F.Mask" "F.Paste")
			(net "GND")
		)
		(pad "E34" smd circle
			(at 6.002782 -9.154922 180)
			(size 0.3048 0.3048)
			(layers "F.Cu" "F.Mask" "F.Paste")
			(net "GND")
		)
		(pad "E36" smd circle
			(at 7.003288 -9.154922 180)
			(size 0.3048 0.3048)
			(layers "F.Cu" "F.Mask" "F.Paste")
			(net "GND")
		)
		(pad "E38" smd circle
			(at 8.003794 -9.154922 180)
			(size 0.3048 0.3048)
			(layers "F.Cu" "F.Mask" "F.Paste")
			(net "GND")
		)
		(pad "E40" smd circle
			(at 9.069832 -9.0043 180)
			(size 0.3048 0.3048)
			(layers "F.Cu" "F.Mask" "F.Paste")
			(net "GND")
		)
		(pad "E42" smd circle
			(at 9.899904 -9.0043 180)
			(size 0.3048 0.3048)
			(layers "F.Cu" "F.Mask" "F.Paste")
			(net "GND")
		)
		(pad "F1" smd circle
			(at -10.31494 -8.504174 180)
			(size 0.4064 0.4064)
			(layers "F.Cu" "F.Mask" "F.Paste")
			(net "TP_PCH_RSVD<1>")
		)
		(pad "F3" smd circle
			(at -9.484868 -8.504174 180)
			(size 0.3048 0.3048)
			(layers "F.Cu" "F.Mask" "F.Paste")
			(net "H_THERMTRIP_LVC1_N")
		)
		(pad "F5" smd circle
			(at -8.654796 -8.504174 180)
			(size 0.3048 0.3048)
			(layers "F.Cu" "F.Mask" "F.Paste")
			(net "FM_PCH_CPU_PWR_DEBUG_N")
		)
		(pad "F8" smd circle
			(at -6.919722 -8.4582 180)
			(size 0.381 0.381)
			(layers "F.Cu" "F.Mask" "F.Paste")
			(net "FM_PCIE_EV_BIF_EN")
		)
		(pad "F11" smd circle
			(at -5.291582 -8.4582 180)
			(size 0.381 0.381)
			(layers "F.Cu" "F.Mask" "F.Paste")
			(net "TP_PCH_CPU_MSMI_N")
		)
		(pad "F15" smd circle
			(at -3.663188 -8.4582 180)
			(size 0.381 0.381)
			(layers "F.Cu" "F.Mask" "F.Paste")
			(net "GND")
		)
		(pad "F18" smd circle
			(at -2.035302 -8.4582 180)
			(size 0.381 0.381)
			(layers "F.Cu" "F.Mask" "F.Paste")
			(net "TP_CLK_100M_PCH_8_DN")
		)
		(pad "F21" smd circle
			(at -0.406908 -8.4582 180)
			(size 0.381 0.381)
			(layers "F.Cu" "F.Mask" "F.Paste")
			(net "TP_CLK_100M_PCH_1_DP")
		)
		(pad "F24" smd circle
			(at 1.220978 -8.4582 180)
			(size 0.381 0.381)
			(layers "F.Cu" "F.Mask" "F.Paste")
			(net "GND")
		)
		(pad "F28" smd circle
			(at 2.849118 -8.4582 180)
			(size 0.381 0.381)
			(layers "F.Cu" "F.Mask" "F.Paste")
			(net "DMI_CPU0_PCH_RX_DP<1>")
		)
		(pad "F31" smd circle
			(at 4.477512 -8.4582 180)
			(size 0.381 0.381)
			(layers "F.Cu" "F.Mask" "F.Paste")
			(net "GND")
		)
		(pad "F34" smd circle
			(at 6.105398 -8.4582 180)
			(size 0.381 0.381)
			(layers "F.Cu" "F.Mask" "F.Paste")
			(net "GND")
		)
		(pad "F37" smd circle
			(at 7.733792 -8.4582 180)
			(size 0.381 0.381)
			(layers "F.Cu" "F.Mask" "F.Paste")
			(net "DMI_CPU0_PCH_RX_DN<7>")
		)
		(pad "F39" smd circle
			(at 8.654796 -8.504174 180)
			(size 0.3048 0.3048)
			(layers "F.Cu" "F.Mask" "F.Paste")
			(net "GND")
		)
		(pad "F41" smd circle
			(at 9.484868 -8.504174 180)
			(size 0.3048 0.3048)
			(layers "F.Cu" "F.Mask" "F.Paste")
			(net "GND")
		)
		(pad "F43" smd circle
			(at 10.31494 -8.504174 180)
			(size 0.4064 0.4064)
			(layers "F.Cu" "F.Mask" "F.Paste")
			(net "GND")
		)
		(pad "G2" smd circle
			(at -9.899904 -8.003794 180)
			(size 0.3048 0.3048)
			(layers "F.Cu" "F.Mask" "F.Paste")
			(net "FM_PCH_RING_OSC_BYPASS_MGPIO_TE")
		)
		(pad "G4" smd circle
			(at -9.069832 -8.003794 180)
			(size 0.3048 0.3048)
			(layers "F.Cu" "F.Mask" "F.Paste")
			(net "FM_PCH_VISA_DEFAULT")
		)
		(pad "G7" smd circle
			(at -7.733792 -7.9883 180)
			(size 0.381 0.381)
			(layers "F.Cu" "F.Mask" "F.Paste")
			(net "H_CPU_ERR1_PCH_R_N")
		)
		(pad "G10" smd circle
			(at -6.105398 -7.9883 180)
			(size 0.381 0.381)
			(layers "F.Cu" "F.Mask" "F.Paste")
			(net "PWRGD_CPUPWRGD_GTL")
		)
		(pad "G13" smd circle
			(at -4.477512 -7.9883 180)
			(size 0.381 0.381)
			(layers "F.Cu" "F.Mask" "F.Paste")
			(net "GND")
		)
		(pad "G16" smd circle
			(at -2.849118 -7.9883 180)
			(size 0.381 0.381)
			(layers "F.Cu" "F.Mask" "F.Paste")
			(net "TP_CLK_100M_PCH_11_DN")
		)
		(pad "G20" smd circle
			(at -1.220978 -7.9883 180)
			(size 0.381 0.381)
			(layers "F.Cu" "F.Mask" "F.Paste")
			(net "GND")
		)
		(pad "G23" smd circle
			(at 0.406908 -7.9883 180)
			(size 0.381 0.381)
			(layers "F.Cu" "F.Mask" "F.Paste")
			(net "TP_CLK_100M_PCH_1_DN")
		)
		(pad "G26" smd circle
			(at 2.035302 -7.9883 180)
			(size 0.381 0.381)
			(layers "F.Cu" "F.Mask" "F.Paste")
			(net "GND")
		)
		(pad "G29" smd circle
			(at 3.663188 -7.9883 180)
			(size 0.381 0.381)
			(layers "F.Cu" "F.Mask" "F.Paste")
			(net "DMI_CPU0_PCH_RX_DN<1>")
		)
	)
)
